(kicad_pcb
	(version 20260206)
	(generator "pcbnew")
	(generator_version "10.0")
	(general
		(thickness 1.6)
		(legacy_teardrops no)
	)
	(paper "A4")
	(title_block
		(title "01162023_DA0F0TEBIF0_F0T_Expander_BD_F_brd_V02_OCP.brd")
		(comment 1 "Grand Teton / footprints 1136-1141 of 9728")
	)
	(layers
		(0 "F.Cu" signal "TOP")
		(4 "In1.Cu" signal "GND")
		(6 "In2.Cu" signal "VCC")
		(8 "In3.Cu" signal "VCC1")
		(10 "In4.Cu" signal "GND1")
		(12 "In5.Cu" signal "IN1")
		(14 "In6.Cu" signal "GND2")
		(16 "In7.Cu" signal "IN2")
		(18 "In8.Cu" signal "GND3")
		(20 "In9.Cu" signal "IN3")
		(22 "In10.Cu" signal "GND4")
		(24 "In11.Cu" signal "IN4")
		(26 "In12.Cu" signal "GND5")
		(28 "In13.Cu" signal "IN5")
		(30 "In14.Cu" signal "GND6")
		(32 "In15.Cu" signal "IN6")
		(34 "In16.Cu" signal "GND7")
		(2 "B.Cu" signal "BOTTOM")
		(9 "F.Adhes" user "F.Adhesive")
		(11 "B.Adhes" user "B.Adhesive")
		(13 "F.Paste" user "Package Geometry/Pastemask Top")
		(15 "B.Paste" user "Package Geometry/Pastemask Bottom")
		(5 "F.SilkS" user "Ref Des/Silkscreen Top")
		(7 "B.SilkS" user "Ref Des/Silkscreen Bottom")
		(1 "F.Mask" user "Board Geometry/Soldermask Top")
		(3 "B.Mask" user "Board Geometry/Soldermask Bottom")
		(17 "Dwgs.User" user "User.Drawings")
		(19 "Cmts.User" user "User.Comments")
		(21 "Eco1.User" user "User.Eco1")
		(23 "Eco2.User" user "User.Eco2")
		(25 "Edge.Cuts" user "Board Geometry/Outline")
		(27 "Margin" user)
		(31 "F.CrtYd" user "Package Geometry/Place Bound Top")
		(29 "B.CrtYd" user "Package Geometry/Place Bound Bottom")
		(35 "F.Fab" user "Ref Des/Assembly Top")
		(33 "B.Fab" user "Ref Des/Assembly Bottom")
	)
	(footprint ""
		(layer "F.Cu")
		(at 353.95027 -50.96383 180)
		(property "Reference" "PC551"
			(at 0 0 180)
			(layer "F.SilkS")
			(hide yes)
			(effects
				(font
					(size 1.27 1.27)
				)
			)
		)
		(property "Value" ""
			(at 0 0 180)
			(layer "F.Fab")
			(effects
				(font
					(size 1.27 1.27)
				)
			)
		)
		(duplicate_pad_numbers_are_jumpers no)
		(fp_line
			(start 1.524 0.762)
			(end -1.524 0.762)
			(stroke
				(width 0.1524)
				(type default)
			)
			(layer "F.SilkS")
		)
		(fp_line
			(start 1.524 -0.762)
			(end 1.524 0.762)
			(stroke
				(width 0.1524)
				(type default)
			)
			(layer "F.SilkS")
		)
		(fp_line
			(start -1.524 0.762)
			(end -1.524 -0.762)
			(stroke
				(width 0.1524)
				(type default)
			)
			(layer "F.SilkS")
		)
		(fp_line
			(start -1.524 -0.762)
			(end 1.524 -0.762)
			(stroke
				(width 0.1524)
				(type default)
			)
			(layer "F.SilkS")
		)
		(fp_line
			(start 1.1049 0.724916)
			(end 1.1049 -0.724916)
			(stroke
				(width 0.1)
				(type default)
			)
			(layer "F.Fab")
		)
		(fp_line
			(start 1.1049 -0.724916)
			(end -1.1049 -0.724916)
			(stroke
				(width 0.1)
				(type default)
			)
			(layer "F.Fab")
		)
		(fp_line
			(start -1.1049 0.724916)
			(end 1.1049 0.724916)
			(stroke
				(width 0.1)
				(type default)
			)
			(layer "F.Fab")
		)
		(fp_line
			(start -1.1049 -0.724916)
			(end -1.1049 0.724916)
			(stroke
				(width 0.1)
				(type default)
			)
			(layer "F.Fab")
		)
		(pad "1" smd rect
			(at -0.889 0)
			(size 1.016 1.27)
			(layers "F.Cu" "F.Mask" "F.Paste")
			(net "P3V3_SSD12")
		)
		(pad "2" smd rect
			(at 0.889 0)
			(size 1.016 1.27)
			(layers "F.Cu" "F.Mask" "F.Paste")
			(net "GND")
		)
	)
	(footprint ""
		(layer "F.Cu")
		(at 45.526706 -55.418228 90)
		(property "Reference" "PC368"
			(at 0 0 90)
			(layer "F.SilkS")
			(hide yes)
			(effects
				(font
					(size 1.27 1.27)
				)
			)
		)
		(property "Value" ""
			(at 0 0 90)
			(layer "F.Fab")
			(effects
				(font
					(size 1.27 1.27)
				)
			)
		)
		(duplicate_pad_numbers_are_jumpers no)
		(fp_line
			(start 0.7874 -0.4064)
			(end 0.7874 0.4064)
			(stroke
				(width 0.1524)
				(type default)
			)
			(layer "F.SilkS")
		)
		(fp_line
			(start -0.7874 -0.4064)
			(end 0.7874 -0.4064)
			(stroke
				(width 0.1524)
				(type default)
			)
			(layer "F.SilkS")
		)
		(fp_line
			(start 0.7874 0.4064)
			(end -0.7874 0.4064)
			(stroke
				(width 0.1524)
				(type default)
			)
			(layer "F.SilkS")
		)
		(fp_line
			(start -0.7874 0.4064)
			(end -0.7874 -0.4064)
			(stroke
				(width 0.1524)
				(type default)
			)
			(layer "F.SilkS")
		)
		(fp_line
			(start -0.12065 -0.305054)
			(end -0.12065 -0.2794)
			(stroke
				(width 0.1)
				(type default)
			)
			(layer "F.Fab")
		)
		(fp_line
			(start -0.67945 -0.305054)
			(end -0.12065 -0.305054)
			(stroke
				(width 0.1)
				(type default)
			)
			(layer "F.Fab")
		)
		(fp_line
			(start 0.67945 -0.3048)
			(end 0.67945 0.3048)
			(stroke
				(width 0.1)
				(type default)
			)
			(layer "F.Fab")
		)
		(fp_line
			(start 0.12065 -0.3048)
			(end 0.67945 -0.3048)
			(stroke
				(width 0.1)
				(type default)
			)
			(layer "F.Fab")
		)
		(fp_line
			(start 0.12065 -0.2794)
			(end 0.12065 -0.3048)
			(stroke
				(width 0.1)
				(type default)
			)
			(layer "F.Fab")
		)
		(fp_line
			(start -0.12065 -0.2794)
			(end 0.12065 -0.2794)
			(stroke
				(width 0.1)
				(type default)
			)
			(layer "F.Fab")
		)
		(fp_line
			(start 0.120396 0.2794)
			(end -0.12065 0.2794)
			(stroke
				(width 0.1)
				(type default)
			)
			(layer "F.Fab")
		)
		(fp_line
			(start -0.12065 0.2794)
			(end -0.12065 0.3048)
			(stroke
				(width 0.1)
				(type default)
			)
			(layer "F.Fab")
		)
		(fp_line
			(start 0.67945 0.3048)
			(end 0.120396 0.3048)
			(stroke
				(width 0.1)
				(type default)
			)
			(layer "F.Fab")
		)
		(fp_line
			(start 0.120396 0.3048)
			(end 0.120396 0.2794)
			(stroke
				(width 0.1)
				(type default)
			)
			(layer "F.Fab")
		)
		(fp_line
			(start -0.12065 0.3048)
			(end -0.67945 0.3048)
			(stroke
				(width 0.1)
				(type default)
			)
			(layer "F.Fab")
		)
		(fp_line
			(start -0.67945 0.3048)
			(end -0.67945 -0.305054)
			(stroke
				(width 0.1)
				(type default)
			)
			(layer "F.Fab")
		)
		(pad "1" smd circle
			(at -0.40005 0 90)
			(size 0 0)
			(layers "F.Cu" "F.Mask" "F.Paste")
			(net "P12V_SSD1_R")
		)
		(pad "2" smd circle
			(at 0.40005 0 90)
			(size 0 0)
			(layers "F.Cu" "F.Mask" "F.Paste")
			(net "GND")
		)
	)
	(footprint ""
		(layer "F.Cu")
		(at 92.019628 -298.792646 -90)
		(property "Reference" "R3886"
			(at 0 0 270)
			(layer "F.SilkS")
			(hide yes)
			(effects
				(font
					(size 1.27 1.27)
				)
			)
		)
		(property "Value" ""
			(at 0 0 270)
			(layer "F.Fab")
			(effects
				(font
					(size 1.27 1.27)
				)
			)
		)
		(duplicate_pad_numbers_are_jumpers no)
		(fp_line
			(start -0.7874 0.4064)
			(end -0.7874 -0.4064)
			(stroke
				(width 0.1524)
				(type default)
			)
			(layer "F.SilkS")
		)
		(fp_line
			(start 0.7874 0.4064)
			(end -0.7874 0.4064)
			(stroke
				(width 0.1524)
				(type default)
			)
			(layer "F.SilkS")
		)
		(fp_line
			(start -0.7874 -0.4064)
			(end 0.7874 -0.4064)
			(stroke
				(width 0.1524)
				(type default)
			)
			(layer "F.SilkS")
		)
		(fp_line
			(start 0.7874 -0.4064)
			(end 0.7874 0.4064)
			(stroke
				(width 0.1524)
				(type default)
			)
			(layer "F.SilkS")
		)
		(fp_line
			(start -0.67945 0.3048)
			(end -0.67945 -0.305054)
			(stroke
				(width 0.1)
				(type default)
			)
			(layer "F.Fab")
		)
		(fp_line
			(start -0.12065 0.3048)
			(end -0.67945 0.3048)
			(stroke
				(width 0.1)
				(type default)
			)
			(layer "F.Fab")
		)
		(fp_line
			(start 0.120396 0.3048)
			(end 0.120396 0.2794)
			(stroke
				(width 0.1)
				(type default)
			)
			(layer "F.Fab")
		)
		(fp_line
			(start 0.67945 0.3048)
			(end 0.120396 0.3048)
			(stroke
				(width 0.1)
				(type default)
			)
			(layer "F.Fab")
		)
		(fp_line
			(start -0.12065 0.2794)
			(end -0.12065 0.3048)
			(stroke
				(width 0.1)
				(type default)
			)
			(layer "F.Fab")
		)
		(fp_line
			(start 0.120396 0.2794)
			(end -0.12065 0.2794)
			(stroke
				(width 0.1)
				(type default)
			)
			(layer "F.Fab")
		)
		(fp_line
			(start -0.12065 -0.2794)
			(end 0.12065 -0.2794)
			(stroke
				(width 0.1)
				(type default)
			)
			(layer "F.Fab")
		)
		(fp_line
			(start 0.12065 -0.2794)
			(end 0.12065 -0.3048)
			(stroke
				(width 0.1)
				(type default)
			)
			(layer "F.Fab")
		)
		(fp_line
			(start 0.12065 -0.3048)
			(end 0.67945 -0.3048)
			(stroke
				(width 0.1)
				(type default)
			)
			(layer "F.Fab")
		)
		(fp_line
			(start 0.67945 -0.3048)
			(end 0.67945 0.3048)
			(stroke
				(width 0.1)
				(type default)
			)
			(layer "F.Fab")
		)
		(fp_line
			(start -0.67945 -0.305054)
			(end -0.12065 -0.305054)
			(stroke
				(width 0.1)
				(type default)
			)
			(layer "F.Fab")
		)
		(fp_line
			(start -0.12065 -0.305054)
			(end -0.12065 -0.2794)
			(stroke
				(width 0.1)
				(type default)
			)
			(layer "F.Fab")
		)
		(pad "1" smd circle
			(at -0.40005 0 270)
			(size 0 0)
			(layers "F.Cu" "F.Mask" "F.Paste")
			(net "I2C_PEX0_HOST_SCL")
		)
		(pad "2" smd circle
			(at 0.40005 0 270)
			(size 0 0)
			(layers "F.Cu" "F.Mask" "F.Paste")
			(net "I2C_PEX0_HOST_R_SCL")
		)
	)
	(footprint ""
		(layer "F.Cu")
		(at 142.343886 -48.93691 180)
		(property "Reference" "R556"
			(at 0 0 180)
			(layer "F.SilkS")
			(hide yes)
			(effects
				(font
					(size 1.27 1.27)
				)
			)
		)
		(property "Value" ""
			(at 0 0 180)
			(layer "F.Fab")
			(effects
				(font
					(size 1.27 1.27)
				)
			)
		)
		(duplicate_pad_numbers_are_jumpers no)
		(fp_line
			(start 0.7874 0.4064)
			(end -0.7874 0.4064)
			(stroke
				(width 0.1524)
				(type default)
			)
			(layer "F.SilkS")
		)
		(fp_line
			(start 0.7874 -0.4064)
			(end 0.7874 0.4064)
			(stroke
				(width 0.1524)
				(type default)
			)
			(layer "F.SilkS")
		)
		(fp_line
			(start -0.7874 0.4064)
			(end -0.7874 -0.4064)
			(stroke
				(width 0.1524)
				(type default)
			)
			(layer "F.SilkS")
		)
		(fp_line
			(start -0.7874 -0.4064)
			(end 0.7874 -0.4064)
			(stroke
				(width 0.1524)
				(type default)
			)
			(layer "F.SilkS")
		)
		(fp_line
			(start 0.67945 0.3048)
			(end 0.120396 0.3048)
			(stroke
				(width 0.1)
				(type default)
			)
			(layer "F.Fab")
		)
		(fp_line
			(start 0.67945 -0.3048)
			(end 0.67945 0.3048)
			(stroke
				(width 0.1)
				(type default)
			)
			(layer "F.Fab")
		)
		(fp_line
			(start 0.12065 -0.2794)
			(end 0.12065 -0.3048)
			(stroke
				(width 0.1)
				(type default)
			)
			(layer "F.Fab")
		)
		(fp_line
			(start 0.12065 -0.3048)
			(end 0.67945 -0.3048)
			(stroke
				(width 0.1)
				(type default)
			)
			(layer "F.Fab")
		)
		(fp_line
			(start 0.120396 0.3048)
			(end 0.120396 0.2794)
			(stroke
				(width 0.1)
				(type default)
			)
			(layer "F.Fab")
		)
		(fp_line
			(start 0.120396 0.2794)
			(end -0.12065 0.2794)
			(stroke
				(width 0.1)
				(type default)
			)
			(layer "F.Fab")
		)
		(fp_line
			(start -0.12065 0.3048)
			(end -0.67945 0.3048)
			(stroke
				(width 0.1)
				(type default)
			)
			(layer "F.Fab")
		)
		(fp_line
			(start -0.12065 0.2794)
			(end -0.12065 0.3048)
			(stroke
				(width 0.1)
				(type default)
			)
			(layer "F.Fab")
		)
		(fp_line
			(start -0.12065 -0.2794)
			(end 0.12065 -0.2794)
			(stroke
				(width 0.1)
				(type default)
			)
			(layer "F.Fab")
		)
		(fp_line
			(start -0.12065 -0.305054)
			(end -0.12065 -0.2794)
			(stroke
				(width 0.1)
				(type default)
			)
			(layer "F.Fab")
		)
		(fp_line
			(start -0.67945 0.3048)
			(end -0.67945 -0.305054)
			(stroke
				(width 0.1)
				(type default)
			)
			(layer "F.Fab")
		)
		(fp_line
			(start -0.67945 -0.305054)
			(end -0.12065 -0.305054)
			(stroke
				(width 0.1)
				(type default)
			)
			(layer "F.Fab")
		)
		(pad "1" smd circle
			(at -0.40005 0 180)
			(size 0 0)
			(layers "F.Cu" "F.Mask" "F.Paste")
			(net "SMB_BIC_I2C6_MUX_SSD_0_7_ADC_R_SDA")
		)
		(pad "2" smd circle
			(at 0.40005 0 180)
			(size 0 0)
			(layers "F.Cu" "F.Mask" "F.Paste")
			(net "SMB_SSD4_ADC_SDA")
		)
	)
	(footprint ""
		(layer "F.Cu")
		(at 126.169166 -118.343426 90)
		(property "Reference" "R5958"
			(at 0 0 90)
			(layer "F.SilkS")
			(hide yes)
			(effects
				(font
					(size 1.27 1.27)
				)
			)
		)
		(property "Value" ""
			(at 0 0 90)
			(layer "F.Fab")
			(effects
				(font
					(size 1.27 1.27)
				)
			)
		)
		(duplicate_pad_numbers_are_jumpers no)
		(fp_line
			(start 0.7874 -0.4064)
			(end 0.7874 0.4064)
			(stroke
				(width 0.1524)
				(type default)
			)
			(layer "F.SilkS")
		)
		(fp_line
			(start -0.7874 -0.4064)
			(end 0.7874 -0.4064)
			(stroke
				(width 0.1524)
				(type default)
			)
			(layer "F.SilkS")
		)
		(fp_line
			(start 0.7874 0.4064)
			(end -0.7874 0.4064)
			(stroke
				(width 0.1524)
				(type default)
			)
			(layer "F.SilkS")
		)
		(fp_line
			(start -0.7874 0.4064)
			(end -0.7874 -0.4064)
			(stroke
				(width 0.1524)
				(type default)
			)
			(layer "F.SilkS")
		)
		(fp_line
			(start -0.12065 -0.305054)
			(end -0.12065 -0.2794)
			(stroke
				(width 0.1)
				(type default)
			)
			(layer "F.Fab")
		)
		(fp_line
			(start -0.67945 -0.305054)
			(end -0.12065 -0.305054)
			(stroke
				(width 0.1)
				(type default)
			)
			(layer "F.Fab")
		)
		(fp_line
			(start 0.67945 -0.3048)
			(end 0.67945 0.3048)
			(stroke
				(width 0.1)
				(type default)
			)
			(layer "F.Fab")
		)
		(fp_line
			(start 0.12065 -0.3048)
			(end 0.67945 -0.3048)
			(stroke
				(width 0.1)
				(type default)
			)
			(layer "F.Fab")
		)
		(fp_line
			(start 0.12065 -0.2794)
			(end 0.12065 -0.3048)
			(stroke
				(width 0.1)
				(type default)
			)
			(layer "F.Fab")
		)
		(fp_line
			(start -0.12065 -0.2794)
			(end 0.12065 -0.2794)
			(stroke
				(width 0.1)
				(type default)
			)
			(layer "F.Fab")
		)
		(fp_line
			(start 0.120396 0.2794)
			(end -0.12065 0.2794)
			(stroke
				(width 0.1)
				(type default)
			)
			(layer "F.Fab")
		)
		(fp_line
			(start -0.12065 0.2794)
			(end -0.12065 0.3048)
			(stroke
				(width 0.1)
				(type default)
			)
			(layer "F.Fab")
		)
		(fp_line
			(start 0.67945 0.3048)
			(end 0.120396 0.3048)
			(stroke
				(width 0.1)
				(type default)
			)
			(layer "F.Fab")
		)
		(fp_line
			(start 0.120396 0.3048)
			(end 0.120396 0.2794)
			(stroke
				(width 0.1)
				(type default)
			)
			(layer "F.Fab")
		)
		(fp_line
			(start -0.12065 0.3048)
			(end -0.67945 0.3048)
			(stroke
				(width 0.1)
				(type default)
			)
			(layer "F.Fab")
		)
		(fp_line
			(start -0.67945 0.3048)
			(end -0.67945 -0.305054)
			(stroke
				(width 0.1)
				(type default)
			)
			(layer "F.Fab")
		)
		(pad "1" smd circle
			(at -0.40005 0 90)
			(size 0 0)
			(layers "F.Cu" "F.Mask" "F.Paste")
			(net "PWRGD_P3V3_NIC2_D")
		)
		(pad "2" smd circle
			(at 0.40005 0 90)
			(size 0 0)
			(layers "F.Cu" "F.Mask" "F.Paste")
			(net "PWRGD_P3V3_NIC2_R")
		)
	)
	(footprint ""
		(layer "F.Cu")
		(at 455.818494 -120.53824 180)
		(property "Reference" "R6049"
			(at 0 0 180)
			(layer "F.SilkS")
			(hide yes)
			(effects
				(font
					(size 1.27 1.27)
				)
			)
		)
		(property "Value" ""
			(at 0 0 180)
			(layer "F.Fab")
			(effects
				(font
					(size 1.27 1.27)
				)
			)
		)
		(duplicate_pad_numbers_are_jumpers no)
		(fp_line
			(start 0.7874 0.4064)
			(end -0.7874 0.4064)
			(stroke
				(width 0.1524)
				(type default)
			)
			(layer "F.SilkS")
		)
		(fp_line
			(start 0.7874 -0.4064)
			(end 0.7874 0.4064)
			(stroke
				(width 0.1524)
				(type default)
			)
			(layer "F.SilkS")
		)
		(fp_line
			(start -0.7874 0.4064)
			(end -0.7874 -0.4064)
			(stroke
				(width 0.1524)
				(type default)
			)
			(layer "F.SilkS")
		)
		(fp_line
			(start -0.7874 -0.4064)
			(end 0.7874 -0.4064)
			(stroke
				(width 0.1524)
				(type default)
			)
			(layer "F.SilkS")
		)
		(fp_line
			(start 0.67945 0.3048)
			(end 0.120396 0.3048)
			(stroke
				(width 0.1)
				(type default)
			)
			(layer "F.Fab")
		)
		(fp_line
			(start 0.67945 -0.3048)
			(end 0.67945 0.3048)
			(stroke
				(width 0.1)
				(type default)
			)
			(layer "F.Fab")
		)
		(fp_line
			(start 0.12065 -0.2794)
			(end 0.12065 -0.3048)
			(stroke
				(width 0.1)
				(type default)
			)
			(layer "F.Fab")
		)
		(fp_line
			(start 0.12065 -0.3048)
			(end 0.67945 -0.3048)
			(stroke
				(width 0.1)
				(type default)
			)
			(layer "F.Fab")
		)
		(fp_line
			(start 0.120396 0.3048)
			(end 0.120396 0.2794)
			(stroke
				(width 0.1)
				(type default)
			)
			(layer "F.Fab")
		)
		(fp_line
			(start 0.120396 0.2794)
			(end -0.12065 0.2794)
			(stroke
				(width 0.1)
				(type default)
			)
			(layer "F.Fab")
		)
		(fp_line
			(start -0.12065 0.3048)
			(end -0.67945 0.3048)
			(stroke
				(width 0.1)
				(type default)
			)
			(layer "F.Fab")
		)
		(fp_line
			(start -0.12065 0.2794)
			(end -0.12065 0.3048)
			(stroke
				(width 0.1)
				(type default)
			)
			(layer "F.Fab")
		)
		(fp_line
			(start -0.12065 -0.2794)
			(end 0.12065 -0.2794)
			(stroke
				(width 0.1)
				(type default)
			)
			(layer "F.Fab")
		)
		(fp_line
			(start -0.12065 -0.305054)
			(end -0.12065 -0.2794)
			(stroke
				(width 0.1)
				(type default)
			)
			(layer "F.Fab")
		)
		(fp_line
			(start -0.67945 0.3048)
			(end -0.67945 -0.305054)
			(stroke
				(width 0.1)
				(type default)
			)
			(layer "F.Fab")
		)
		(fp_line
			(start -0.67945 -0.305054)
			(end -0.12065 -0.305054)
			(stroke
				(width 0.1)
				(type default)
			)
			(layer "F.Fab")
		)
		(pad "1" smd circle
			(at -0.40005 0 180)
			(size 0 0)
			(layers "F.Cu" "F.Mask" "F.Paste")
			(net "P5V_AUX")
		)
		(pad "2" smd circle
			(at 0.40005 0 180)
			(size 0 0)
			(layers "F.Cu" "F.Mask" "F.Paste")
			(net "P3V3_NIC7_PG_G2")
		)
	)
)
